(kicad_pcb
	(version 20260206)
	(generator "pcbnew")
	(generator_version "10.0")
	(general
		(thickness 1.6)
		(legacy_teardrops no)
	)
	(paper "A4")
	(title_block
		(title "9052_F0T_PDB_Converter_Brick_F_V03_1208_1600_OCP.brd")
		(comment 1 "Grand Teton / footprints 279-285 of 578")
	)
	(layers
		(0 "F.Cu" signal "TOP")
		(4 "In1.Cu" signal "GND")
		(6 "In2.Cu" signal "IN1")
		(8 "In3.Cu" signal "GND1")
		(10 "In4.Cu" signal "VCC")
		(12 "In5.Cu" signal "VCC1")
		(14 "In6.Cu" signal "GND2")
		(16 "In7.Cu" signal "IN2")
		(18 "In8.Cu" signal "GND3")
		(2 "B.Cu" signal "BOTTOM")
		(9 "F.Adhes" user "F.Adhesive")
		(11 "B.Adhes" user "B.Adhesive")
		(13 "F.Paste" user "Package Geometry/Pastemask Top")
		(15 "B.Paste" user "Package Geometry/Pastemask Bottom")
		(5 "F.SilkS" user "Ref Des/Silkscreen Top")
		(7 "B.SilkS" user "Ref Des/Silkscreen Bottom")
		(1 "F.Mask" user "Board Geometry/Soldermask Top")
		(3 "B.Mask" user "Board Geometry/Soldermask Bottom")
		(17 "Dwgs.User" user "User.Drawings")
		(19 "Cmts.User" user "User.Comments")
		(21 "Eco1.User" user "User.Eco1")
		(23 "Eco2.User" user "User.Eco2")
		(25 "Edge.Cuts" user "Board Geometry/Outline")
		(27 "Margin" user)
		(31 "F.CrtYd" user "Package Geometry/Place Bound Top")
		(29 "B.CrtYd" user "Package Geometry/Place Bound Bottom")
		(35 "F.Fab" user "Ref Des/Assembly Top")
		(33 "B.Fab" user "Ref Des/Assembly Bottom")
	)
	(footprint ""
		(layer "F.Cu")
		(at 285.995872 -57.92724)
		(property "Reference" "PQ15"
			(at -1.905 -2.25933 0)
			(unlocked yes)
			(layer "F.SilkS")
			(effects
				(font
					(size 0.7874 0.5842)
					(thickness 0.1524)
				)
				(justify left)
			)
		)
		(property "Value" ""
			(at 0 0 0)
			(layer "F.Fab")
			(effects
				(font
					(size 1.27 1.27)
				)
			)
		)
		(duplicate_pad_numbers_are_jumpers no)
		(fp_line
			(start -1.905 -1.651)
			(end 1.905 -1.651)
			(stroke
				(width 0.1524)
				(type default)
			)
			(layer "F.SilkS")
		)
		(fp_line
			(start -1.905 1.651)
			(end -1.905 -1.651)
			(stroke
				(width 0.1524)
				(type default)
			)
			(layer "F.SilkS")
		)
		(fp_line
			(start 1.905 -1.651)
			(end 1.905 1.651)
			(stroke
				(width 0.1524)
				(type default)
			)
			(layer "F.SilkS")
		)
		(fp_line
			(start 1.905 1.651)
			(end -1.905 1.651)
			(stroke
				(width 0.1524)
				(type default)
			)
			(layer "F.SilkS")
		)
		(fp_line
			(start -1.249934 -1.169924)
			(end -0.649986 -1.169924)
			(stroke
				(width 0.1)
				(type default)
			)
			(layer "F.Fab")
		)
		(fp_line
			(start -1.249934 -0.729996)
			(end -1.249934 -1.169924)
			(stroke
				(width 0.1)
				(type default)
			)
			(layer "F.Fab")
		)
		(fp_line
			(start -1.249934 0.729996)
			(end -0.6985 0.729996)
			(stroke
				(width 0.1)
				(type default)
			)
			(layer "F.Fab")
		)
		(fp_line
			(start -1.249934 1.169924)
			(end -1.249934 0.729996)
			(stroke
				(width 0.1)
				(type default)
			)
			(layer "F.Fab")
		)
		(fp_line
			(start -0.6985 -0.729996)
			(end -1.249934 -0.729996)
			(stroke
				(width 0.1)
				(type default)
			)
			(layer "F.Fab")
		)
		(fp_line
			(start -0.6985 0.729996)
			(end -0.6985 -0.729996)
			(stroke
				(width 0.1)
				(type default)
			)
			(layer "F.Fab")
		)
		(fp_line
			(start -0.649986 -1.524)
			(end 0.6985 -1.524)
			(stroke
				(width 0.1)
				(type default)
			)
			(layer "F.Fab")
		)
		(fp_line
			(start -0.649986 -1.169924)
			(end -0.649986 -1.524)
			(stroke
				(width 0.1)
				(type default)
			)
			(layer "F.Fab")
		)
		(fp_line
			(start -0.649986 1.169924)
			(end -1.249934 1.169924)
			(stroke
				(width 0.1)
				(type default)
			)
			(layer "F.Fab")
		)
		(fp_line
			(start -0.649986 1.524)
			(end -0.649986 1.169924)
			(stroke
				(width 0.1)
				(type default)
			)
			(layer "F.Fab")
		)
		(fp_line
			(start 0.6985 -1.524)
			(end 0.6985 -0.219964)
			(stroke
				(width 0.1)
				(type default)
			)
			(layer "F.Fab")
		)
		(fp_line
			(start 0.6985 -0.219964)
			(end 1.249934 -0.219964)
			(stroke
				(width 0.1)
				(type default)
			)
			(layer "F.Fab")
		)
		(fp_line
			(start 0.6985 0.219964)
			(end 0.6985 1.524)
			(stroke
				(width 0.1)
				(type default)
			)
			(layer "F.Fab")
		)
		(fp_line
			(start 0.6985 1.524)
			(end -0.649986 1.524)
			(stroke
				(width 0.1)
				(type default)
			)
			(layer "F.Fab")
		)
		(fp_line
			(start 1.249934 -0.219964)
			(end 1.249934 0.219964)
			(stroke
				(width 0.1)
				(type default)
			)
			(layer "F.Fab")
		)
		(fp_line
			(start 1.249934 0.219964)
			(end 0.6985 0.219964)
			(stroke
				(width 0.1)
				(type default)
			)
			(layer "F.Fab")
		)
		(pad "B" smd rect
			(at -1.1176 -1.016 270)
			(size 1.016 1.27)
			(layers "F.Cu" "F.Mask" "F.Paste")
			(net "P52V_HS1_TEMP_R")
		)
		(pad "C" smd rect
			(at 1.1176 0 270)
			(size 1.016 1.27)
			(layers "F.Cu" "F.Mask" "F.Paste")
			(net "P52V_HS1_TEMP_R")
		)
		(pad "E" smd rect
			(at -1.1176 1.016 270)
			(size 1.016 1.27)
			(layers "F.Cu" "F.Mask" "F.Paste")
			(net "P52V_HS1_TEMPN_R")
		)
	)
	(footprint ""
		(layer "F.Cu")
		(at 259.334 -24.892 180)
		(property "Reference" "PR92"
			(at 0 0 180)
			(layer "F.SilkS")
			(hide yes)
			(effects
				(font
					(size 1.27 1.27)
				)
			)
		)
		(property "Value" ""
			(at 0 0 180)
			(layer "F.Fab")
			(effects
				(font
					(size 1.27 1.27)
				)
			)
		)
		(duplicate_pad_numbers_are_jumpers no)
		(fp_line
			(start 0.7874 0.4064)
			(end -0.7874 0.4064)
			(stroke
				(width 0.1524)
				(type default)
			)
			(layer "F.SilkS")
		)
		(fp_line
			(start 0.7874 -0.4064)
			(end 0.7874 0.4064)
			(stroke
				(width 0.1524)
				(type default)
			)
			(layer "F.SilkS")
		)
		(fp_line
			(start -0.7874 0.4064)
			(end -0.7874 -0.4064)
			(stroke
				(width 0.1524)
				(type default)
			)
			(layer "F.SilkS")
		)
		(fp_line
			(start -0.7874 -0.4064)
			(end 0.7874 -0.4064)
			(stroke
				(width 0.1524)
				(type default)
			)
			(layer "F.SilkS")
		)
		(fp_line
			(start 0.67945 0.3048)
			(end 0.120396 0.3048)
			(stroke
				(width 0.1)
				(type default)
			)
			(layer "F.Fab")
		)
		(fp_line
			(start 0.67945 -0.3048)
			(end 0.67945 0.3048)
			(stroke
				(width 0.1)
				(type default)
			)
			(layer "F.Fab")
		)
		(fp_line
			(start 0.12065 -0.2794)
			(end 0.12065 -0.3048)
			(stroke
				(width 0.1)
				(type default)
			)
			(layer "F.Fab")
		)
		(fp_line
			(start 0.12065 -0.3048)
			(end 0.67945 -0.3048)
			(stroke
				(width 0.1)
				(type default)
			)
			(layer "F.Fab")
		)
		(fp_line
			(start 0.120396 0.3048)
			(end 0.120396 0.2794)
			(stroke
				(width 0.1)
				(type default)
			)
			(layer "F.Fab")
		)
		(fp_line
			(start 0.120396 0.2794)
			(end -0.12065 0.2794)
			(stroke
				(width 0.1)
				(type default)
			)
			(layer "F.Fab")
		)
		(fp_line
			(start -0.12065 0.3048)
			(end -0.67945 0.3048)
			(stroke
				(width 0.1)
				(type default)
			)
			(layer "F.Fab")
		)
		(fp_line
			(start -0.12065 0.2794)
			(end -0.12065 0.3048)
			(stroke
				(width 0.1)
				(type default)
			)
			(layer "F.Fab")
		)
		(fp_line
			(start -0.12065 -0.2794)
			(end 0.12065 -0.2794)
			(stroke
				(width 0.1)
				(type default)
			)
			(layer "F.Fab")
		)
		(fp_line
			(start -0.12065 -0.305054)
			(end -0.12065 -0.2794)
			(stroke
				(width 0.1)
				(type default)
			)
			(layer "F.Fab")
		)
		(fp_line
			(start -0.67945 0.3048)
			(end -0.67945 -0.305054)
			(stroke
				(width 0.1)
				(type default)
			)
			(layer "F.Fab")
		)
		(fp_line
			(start -0.67945 -0.305054)
			(end -0.12065 -0.305054)
			(stroke
				(width 0.1)
				(type default)
			)
			(layer "F.Fab")
		)
		(pad "1" smd circle
			(at -0.40005 0 180)
			(size 0 0)
			(layers "F.Cu" "F.Mask" "F.Paste")
			(net "SMB_P52V_HSC_SDA")
		)
		(pad "2" smd circle
			(at 0.40005 0 180)
			(size 0 0)
			(layers "F.Cu" "F.Mask" "F.Paste")
			(net "SMB_P52V_VPDB_DEBUG_SDA")
		)
	)
	(footprint ""
		(layer "F.Cu")
		(at 42.046906 -136.906 90)
		(property "Reference" "PC73"
			(at 6.06933 1.133094 0)
			(unlocked yes)
			(layer "F.SilkS")
			(effects
				(font
					(size 0.7874 0.5842)
					(thickness 0.1524)
				)
				(justify left)
			)
		)
		(property "Value" ""
			(at 0 0 90)
			(layer "F.Fab")
			(effects
				(font
					(size 1.27 1.27)
				)
			)
		)
		(duplicate_pad_numbers_are_jumpers no)
		(fp_line
			(start 5.2578 2.499868)
			(end -5.2578 2.499868)
			(stroke
				(width 0.1524)
				(type default)
			)
			(layer "F.SilkS")
		)
		(fp_circle
			(center 0 2.500122)
			(end 0 7.758176)
			(stroke
				(width 0.1524)
				(type default)
			)
			(fill no)
			(layer "F.SilkS")
		)
		(fp_poly
			(pts
				(arc
					(start 5.2578 2.499868)
					(mid 0 7.757922)
					(end -5.2578 2.499868)
				)
			)
			(stroke
				(width 0)
				(type default)
			)
			(fill yes)
			(layer "F.SilkS")
		)
		(fp_circle
			(center 0 2.500122)
			(end 0 7.758176)
			(stroke
				(width 0.1)
				(type default)
			)
			(fill no)
			(layer "F.Fab")
		)
		(pad "1" thru_hole rect
			(at 0 0)
			(size 1.5748 1.5748)
			(drill 1.0668)
			(layers "*.Cu" "*.Mask")
			(remove_unused_layers no)
			(net "P52V_HS_FILTER")
			(clearance 0)
			(padstack
				(mode front_inner_back)
				(layer "Inner"
					(shape circle)
					(size 1.5748 1.5748)
					(clearance 0)
				)
				(layer "B.Cu"
					(shape rect)
					(size 1.5748 1.5748)
					(clearance 0)
				)
			)
		)
		(pad "2" thru_hole circle
			(at 0 4.99999)
			(size 1.5748 1.5748)
			(drill 1.0668)
			(layers "*.Cu" "*.Mask")
			(remove_unused_layers no)
			(net "GND")
			(clearance 0)
		)
	)
	(footprint ""
		(layer "F.Cu")
		(at 38.6588 -60.5282 -90)
		(property "Reference" "C95"
			(at 0 0 270)
			(layer "F.SilkS")
			(hide yes)
			(effects
				(font
					(size 1.27 1.27)
				)
			)
		)
		(property "Value" ""
			(at 0 0 270)
			(layer "F.Fab")
			(effects
				(font
					(size 1.27 1.27)
				)
			)
		)
		(duplicate_pad_numbers_are_jumpers no)
		(fp_line
			(start -1.2954 0.5842)
			(end -1.2954 -0.5842)
			(stroke
				(width 0.1524)
				(type default)
			)
			(layer "F.SilkS")
		)
		(fp_line
			(start 1.2954 0.5842)
			(end -1.2954 0.5842)
			(stroke
				(width 0.1524)
				(type default)
			)
			(layer "F.SilkS")
		)
		(fp_line
			(start -1.2954 -0.5842)
			(end 1.2954 -0.5842)
			(stroke
				(width 0.1524)
				(type default)
			)
			(layer "F.SilkS")
		)
		(fp_line
			(start 1.2954 -0.5842)
			(end 1.2954 0.5842)
			(stroke
				(width 0.1524)
				(type default)
			)
			(layer "F.SilkS")
		)
		(fp_line
			(start -0.8636 0.4572)
			(end -0.8636 0.4064)
			(stroke
				(width 0.1)
				(type default)
			)
			(layer "F.Fab")
		)
		(fp_line
			(start 0.8636 0.4572)
			(end -0.8636 0.4572)
			(stroke
				(width 0.1)
				(type default)
			)
			(layer "F.Fab")
		)
		(fp_line
			(start -1.1938 0.4064)
			(end -1.1938 -0.4064)
			(stroke
				(width 0.1)
				(type default)
			)
			(layer "F.Fab")
		)
		(fp_line
			(start -0.8636 0.4064)
			(end -1.1938 0.4064)
			(stroke
				(width 0.1)
				(type default)
			)
			(layer "F.Fab")
		)
		(fp_line
			(start 0.8636 0.4064)
			(end 0.8636 0.4572)
			(stroke
				(width 0.1)
				(type default)
			)
			(layer "F.Fab")
		)
		(fp_line
			(start 1.1938 0.4064)
			(end 0.8636 0.4064)
			(stroke
				(width 0.1)
				(type default)
			)
			(layer "F.Fab")
		)
		(fp_line
			(start -1.1938 -0.4064)
			(end -0.8636 -0.4064)
			(stroke
				(width 0.1)
				(type default)
			)
			(layer "F.Fab")
		)
		(fp_line
			(start -0.8636 -0.4064)
			(end -0.8636 -0.4572)
			(stroke
				(width 0.1)
				(type default)
			)
			(layer "F.Fab")
		)
		(fp_line
			(start 0.8636 -0.4064)
			(end 1.1938 -0.4064)
			(stroke
				(width 0.1)
				(type default)
			)
			(layer "F.Fab")
		)
		(fp_line
			(start 1.1938 -0.4064)
			(end 1.1938 0.4064)
			(stroke
				(width 0.1)
				(type default)
			)
			(layer "F.Fab")
		)
		(fp_line
			(start -0.8636 -0.4572)
			(end 0.8636 -0.4572)
			(stroke
				(width 0.1)
				(type default)
			)
			(layer "F.Fab")
		)
		(fp_line
			(start 0.8636 -0.4572)
			(end 0.8636 -0.4064)
			(stroke
				(width 0.1)
				(type default)
			)
			(layer "F.Fab")
		)
		(pad "1" smd rect
			(at -0.7366 0 180)
			(size 0.7112 0.8128)
			(layers "F.Cu" "F.Mask" "F.Paste")
			(net "GND")
		)
		(pad "2" smd rect
			(at 0.7366 0 180)
			(size 0.7112 0.8128)
			(layers "F.Cu" "F.Mask" "F.Paste")
			(net "P12V_HPDB_0_PD")
		)
	)
	(footprint ""
		(layer "F.Cu")
		(at 136.906 -127.889)
		(property "Reference" "PC20"
			(at 0 0 0)
			(layer "F.SilkS")
			(hide yes)
			(effects
				(font
					(size 1.27 1.27)
				)
			)
		)
		(property "Value" ""
			(at 0 0 0)
			(layer "F.Fab")
			(effects
				(font
					(size 1.27 1.27)
				)
			)
		)
		(duplicate_pad_numbers_are_jumpers no)
		(fp_line
			(start -2.2098 -0.9398)
			(end 2.2098 -0.9398)
			(stroke
				(width 0.1524)
				(type default)
			)
			(layer "F.SilkS")
		)
		(fp_line
			(start -2.2098 0.9398)
			(end -2.2098 -0.9398)
			(stroke
				(width 0.1524)
				(type default)
			)
			(layer "F.SilkS")
		)
		(fp_line
			(start 2.2098 -0.9398)
			(end 2.2098 0.9398)
			(stroke
				(width 0.1524)
				(type default)
			)
			(layer "F.SilkS")
		)
		(fp_line
			(start 2.2098 0.9398)
			(end -2.2098 0.9398)
			(stroke
				(width 0.1524)
				(type default)
			)
			(layer "F.SilkS")
		)
		(fp_line
			(start -1.700022 -0.899922)
			(end 1.700022 -0.899922)
			(stroke
				(width 0.1)
				(type default)
			)
			(layer "F.Fab")
		)
		(fp_line
			(start -1.700022 0.899922)
			(end -1.700022 -0.899922)
			(stroke
				(width 0.1)
				(type default)
			)
			(layer "F.Fab")
		)
		(fp_line
			(start 1.700022 -0.899922)
			(end 1.700022 0.899922)
			(stroke
				(width 0.1)
				(type default)
			)
			(layer "F.Fab")
		)
		(fp_line
			(start 1.700022 0.899922)
			(end -1.700022 0.899922)
			(stroke
				(width 0.1)
				(type default)
			)
			(layer "F.Fab")
		)
		(pad "1" smd rect
			(at -1.4732 0 180)
			(size 1.1684 1.5748)
			(layers "F.Cu" "F.Mask" "F.Paste")
			(net "P52V_HS_FILTER")
		)
		(pad "2" smd rect
			(at 1.4732 0 180)
			(size 1.1684 1.5748)
			(layers "F.Cu" "F.Mask" "F.Paste")
			(net "GND")
		)
	)
	(footprint ""
		(layer "F.Cu")
		(at 299.570394 -88.0745 180)
		(property "Reference" "PR5864"
			(at 0 0 180)
			(layer "F.SilkS")
			(hide yes)
			(effects
				(font
					(size 1.27 1.27)
				)
			)
		)
		(property "Value" ""
			(at 0 0 180)
			(layer "F.Fab")
			(effects
				(font
					(size 1.27 1.27)
				)
			)
		)
		(duplicate_pad_numbers_are_jumpers no)
		(fp_line
			(start 0.7874 0.4064)
			(end -0.7874 0.4064)
			(stroke
				(width 0.1524)
				(type default)
			)
			(layer "F.SilkS")
		)
		(fp_line
			(start 0.7874 -0.4064)
			(end 0.7874 0.4064)
			(stroke
				(width 0.1524)
				(type default)
			)
			(layer "F.SilkS")
		)
		(fp_line
			(start -0.7874 0.4064)
			(end -0.7874 -0.4064)
			(stroke
				(width 0.1524)
				(type default)
			)
			(layer "F.SilkS")
		)
		(fp_line
			(start -0.7874 -0.4064)
			(end 0.7874 -0.4064)
			(stroke
				(width 0.1524)
				(type default)
			)
			(layer "F.SilkS")
		)
		(fp_line
			(start 0.67945 0.3048)
			(end 0.120396 0.3048)
			(stroke
				(width 0.1)
				(type default)
			)
			(layer "F.Fab")
		)
		(fp_line
			(start 0.67945 -0.3048)
			(end 0.67945 0.3048)
			(stroke
				(width 0.1)
				(type default)
			)
			(layer "F.Fab")
		)
		(fp_line
			(start 0.12065 -0.2794)
			(end 0.12065 -0.3048)
			(stroke
				(width 0.1)
				(type default)
			)
			(layer "F.Fab")
		)
		(fp_line
			(start 0.12065 -0.3048)
			(end 0.67945 -0.3048)
			(stroke
				(width 0.1)
				(type default)
			)
			(layer "F.Fab")
		)
		(fp_line
			(start 0.120396 0.3048)
			(end 0.120396 0.2794)
			(stroke
				(width 0.1)
				(type default)
			)
			(layer "F.Fab")
		)
		(fp_line
			(start 0.120396 0.2794)
			(end -0.12065 0.2794)
			(stroke
				(width 0.1)
				(type default)
			)
			(layer "F.Fab")
		)
		(fp_line
			(start -0.12065 0.3048)
			(end -0.67945 0.3048)
			(stroke
				(width 0.1)
				(type default)
			)
			(layer "F.Fab")
		)
		(fp_line
			(start -0.12065 0.2794)
			(end -0.12065 0.3048)
			(stroke
				(width 0.1)
				(type default)
			)
			(layer "F.Fab")
		)
		(fp_line
			(start -0.12065 -0.2794)
			(end 0.12065 -0.2794)
			(stroke
				(width 0.1)
				(type default)
			)
			(layer "F.Fab")
		)
		(fp_line
			(start -0.12065 -0.305054)
			(end -0.12065 -0.2794)
			(stroke
				(width 0.1)
				(type default)
			)
			(layer "F.Fab")
		)
		(fp_line
			(start -0.67945 0.3048)
			(end -0.67945 -0.305054)
			(stroke
				(width 0.1)
				(type default)
			)
			(layer "F.Fab")
		)
		(fp_line
			(start -0.67945 -0.305054)
			(end -0.12065 -0.305054)
			(stroke
				(width 0.1)
				(type default)
			)
			(layer "F.Fab")
		)
		(pad "1" smd circle
			(at -0.40005 0 180)
			(size 0 0)
			(layers "F.Cu" "F.Mask" "F.Paste")
			(net "P52V_HS_4287_S2P")
		)
		(pad "2" smd circle
			(at 0.40005 0 180)
			(size 0 0)
			(layers "F.Cu" "F.Mask" "F.Paste")
			(net "P52V_HS_4287_S2N")
		)
	)
	(footprint ""
		(layer "F.Cu")
		(at 267.589 -47.625 -90)
		(property "Reference" "R5856"
			(at 0 0 270)
			(layer "F.SilkS")
			(hide yes)
			(effects
				(font
					(size 1.27 1.27)
				)
			)
		)
		(property "Value" ""
			(at 0 0 270)
			(layer "F.Fab")
			(effects
				(font
					(size 1.27 1.27)
				)
			)
		)
		(duplicate_pad_numbers_are_jumpers no)
		(fp_line
			(start -0.7874 0.4064)
			(end -0.7874 -0.4064)
			(stroke
				(width 0.1524)
				(type default)
			)
			(layer "F.SilkS")
		)
		(fp_line
			(start 0.7874 0.4064)
			(end -0.7874 0.4064)
			(stroke
				(width 0.1524)
				(type default)
			)
			(layer "F.SilkS")
		)
		(fp_line
			(start -0.7874 -0.4064)
			(end 0.7874 -0.4064)
			(stroke
				(width 0.1524)
				(type default)
			)
			(layer "F.SilkS")
		)
		(fp_line
			(start 0.7874 -0.4064)
			(end 0.7874 0.4064)
			(stroke
				(width 0.1524)
				(type default)
			)
			(layer "F.SilkS")
		)
		(fp_line
			(start -0.67945 0.3048)
			(end -0.67945 -0.305054)
			(stroke
				(width 0.1)
				(type default)
			)
			(layer "F.Fab")
		)
		(fp_line
			(start -0.12065 0.3048)
			(end -0.67945 0.3048)
			(stroke
				(width 0.1)
				(type default)
			)
			(layer "F.Fab")
		)
		(fp_line
			(start 0.120396 0.3048)
			(end 0.120396 0.2794)
			(stroke
				(width 0.1)
				(type default)
			)
			(layer "F.Fab")
		)
		(fp_line
			(start 0.67945 0.3048)
			(end 0.120396 0.3048)
			(stroke
				(width 0.1)
				(type default)
			)
			(layer "F.Fab")
		)
		(fp_line
			(start -0.12065 0.2794)
			(end -0.12065 0.3048)
			(stroke
				(width 0.1)
				(type default)
			)
			(layer "F.Fab")
		)
		(fp_line
			(start 0.120396 0.2794)
			(end -0.12065 0.2794)
			(stroke
				(width 0.1)
				(type default)
			)
			(layer "F.Fab")
		)
		(fp_line
			(start -0.12065 -0.2794)
			(end 0.12065 -0.2794)
			(stroke
				(width 0.1)
				(type default)
			)
			(layer "F.Fab")
		)
		(fp_line
			(start 0.12065 -0.2794)
			(end 0.12065 -0.3048)
			(stroke
				(width 0.1)
				(type default)
			)
			(layer "F.Fab")
		)
		(fp_line
			(start 0.12065 -0.3048)
			(end 0.67945 -0.3048)
			(stroke
				(width 0.1)
				(type default)
			)
			(layer "F.Fab")
		)
		(fp_line
			(start 0.67945 -0.3048)
			(end 0.67945 0.3048)
			(stroke
				(width 0.1)
				(type default)
			)
			(layer "F.Fab")
		)
		(fp_line
			(start -0.67945 -0.305054)
			(end -0.12065 -0.305054)
			(stroke
				(width 0.1)
				(type default)
			)
			(layer "F.Fab")
		)
		(fp_line
			(start -0.12065 -0.305054)
			(end -0.12065 -0.2794)
			(stroke
				(width 0.1)
				(type default)
			)
			(layer "F.Fab")
		)
		(pad "1" smd circle
			(at -0.40005 0 270)
			(size 0 0)
			(layers "F.Cu" "F.Mask" "F.Paste")
			(net "SMB_P52V_HSC_SDA")
		)
		(pad "2" smd circle
			(at 0.40005 0 270)
			(size 0 0)
			(layers "F.Cu" "F.Mask" "F.Paste")
			(net "SMB_P52V_HS1_SDAO")
		)
	)
)
